G04 ================== begin FILE IDENTIFICATION RECORD ==================*
G04 Layout Name:  17301-sa.brd*
G04 Film Name:    L1*
G04 File Format:  Gerber RS274X*
G04 File Origin:  Cadence Allegro 16.6-2015-S079*
G04 Origin Date:  Thu Jun 22 17:49:59 2017*
G04 *
G04 Layer:  VIA CLASS/TOP*
G04 Layer:  PIN/TOP*
G04 Layer:  ETCH/TOP*
G04 Layer:  DRAWING FORMAT/LAYER_PCB_STORY*
G04 Layer:  DRAWING FORMAT/LAYER_L1*
G04 *
G04 Offset:    (0.00 0.00)*
G04 Mirror:    No*
G04 Mode:      Positive*
G04 Rotation:  0*
G04 FullContactRelief:  No*
G04 UndefLineWidth:     6.00*
G04 ================== end FILE IDENTIFICATION RECORD ====================*
%FSLAX35Y35*MOIN*%
%IR0*IPPOS*OFA0.00000B0.00000*MIA0B0*SFA1.00000B1.00000*%
%AMMACRO22*
4,1,40,.013,.017,
-.013,.017,
-.013695,.016939,
-.014368,.016759,
-.015,.016464,
-.015571,.016064,
-.016064,.015571,
-.016464,.015,
-.016759,.014368,
-.016939,.013695,
-.017,.013,
-.017,-.013,
-.016939,-.013695,
-.016759,-.014368,
-.016464,-.015,
-.016064,-.015571,
-.015571,-.016064,
-.015,-.016464,
-.014368,-.016759,
-.013695,-.016939,
-.013,-.017,
.013,-.017,
.013695,-.016939,
.014368,-.016759,
.015,-.016464,
.015571,-.016064,
.016064,-.015571,
.016464,-.015,
.016759,-.014368,
.016939,-.013695,
.017,-.013,
.017,.013,
.016939,.013695,
.016759,.014368,
.016464,.015,
.016064,.015571,
.015571,.016064,
.015,.016464,
.014368,.016759,
.013695,.016939,
.013,.017,
0.0*
%
%ADD22MACRO22*%
%ADD10C,.01*%
%ADD17C,.02*%
%ADD13C,.04*%
%ADD12C,.022*%
%ADD18C,.034*%
%ADD39C,.071*%
%ADD30C,.028*%
%ADD16C,.093*%
%AMMACRO35*
4,1,40,.011,-.007,
.011,.007,
.010939,.007695,
.010759,.008368,
.010464,.009,
.010064,.009571,
.009571,.010064,
.009,.010464,
.008368,.010759,
.007695,.010939,
.007,.011,
-.007,.011,
-.007695,.010939,
-.008368,.010759,
-.009,.010464,
-.009571,.010064,
-.010064,.009571,
-.010464,.009,
-.010759,.008368,
-.010939,.007695,
-.011,.007,
-.011,-.007,
-.010939,-.007695,
-.010759,-.008368,
-.010464,-.009,
-.010064,-.009571,
-.009571,-.010064,
-.009,-.010464,
-.008368,-.010759,
-.007695,-.010939,
-.007,-.011,
.007,-.011,
.007695,-.010939,
.008368,-.010759,
.009,-.010464,
.009571,-.010064,
.010064,-.009571,
.010464,-.009,
.010759,-.008368,
.010939,-.007695,
.011,-.007,
0.0*
%
%ADD35MACRO35*%
%AMMACRO24*
4,1,40,-.012,.008,
-.012,-.008,
-.011939,-.008695,
-.011759,-.009368,
-.011464,-.01,
-.011064,-.010571,
-.010571,-.011064,
-.01,-.011464,
-.009368,-.011759,
-.008695,-.011939,
-.008,-.012,
.008,-.012,
.008695,-.011939,
.009368,-.011759,
.01,-.011464,
.010571,-.011064,
.011064,-.010571,
.011464,-.01,
.011759,-.009368,
.011939,-.008695,
.012,-.008,
.012,.008,
.011939,.008695,
.011759,.009368,
.011464,.01,
.011064,.010571,
.010571,.011064,
.01,.011464,
.009368,.011759,
.008695,.011939,
.008,.012,
-.008,.012,
-.008695,.011939,
-.009368,.011759,
-.01,.011464,
-.010571,.011064,
-.011064,.010571,
-.011464,.01,
-.011759,.009368,
-.011939,.008695,
-.012,.008,
0.0*
%
%ADD24MACRO24*%
%AMMACRO38*
4,1,40,.008,.012,
-.008,.012,
-.008695,.011939,
-.009368,.011759,
-.01,.011464,
-.010571,.011064,
-.011064,.010571,
-.011464,.01,
-.011759,.009368,
-.011939,.008695,
-.012,.008,
-.012,-.008,
-.011939,-.008695,
-.011759,-.009368,
-.011464,-.01,
-.011064,-.010571,
-.010571,-.011064,
-.01,-.011464,
-.009368,-.011759,
-.008695,-.011939,
-.008,-.012,
.008,-.012,
.008695,-.011939,
.009368,-.011759,
.01,-.011464,
.010571,-.011064,
.011064,-.010571,
.011464,-.01,
.011759,-.009368,
.011939,-.008695,
.012,-.008,
.012,.008,
.011939,.008695,
.011759,.009368,
.011464,.01,
.011064,.010571,
.010571,.011064,
.01,.011464,
.009368,.011759,
.008695,.011939,
.008,.012,
0.0*
%
%ADD38MACRO38*%
%AMMACRO36*
4,1,40,.011,-.007,
.011,.007,
.010939,.007695,
.010759,.008368,
.010464,.009,
.010064,.009571,
.009571,.010064,
.009,.010464,
.008368,.010759,
.007695,.010939,
.007,.011,
-.007,.011,
-.007695,.010939,
-.008368,.010759,
-.009,.010464,
-.009571,.010064,
-.010064,.009571,
-.010464,.009,
-.010759,.008368,
-.010939,.007695,
-.011,.007,
-.011,-.007,
-.010939,-.007695,
-.010759,-.008368,
-.010464,-.009,
-.010064,-.009571,
-.009571,-.010064,
-.009,-.010464,
-.008368,-.010759,
-.007695,-.010939,
-.007,-.011,
.007,-.011,
.007695,-.010939,
.008368,-.010759,
.009,-.010464,
.009571,-.010064,
.010064,-.009571,
.010464,-.009,
.010759,-.008368,
.010939,-.007695,
.011,-.007,
0.0*
%
%ADD36MACRO36*%
%AMMACRO23*
4,1,40,-.012,.008,
-.012,-.008,
-.011939,-.008695,
-.011759,-.009368,
-.011464,-.01,
-.011064,-.010571,
-.010571,-.011064,
-.01,-.011464,
-.009368,-.011759,
-.008695,-.011939,
-.008,-.012,
.008,-.012,
.008695,-.011939,
.009368,-.011759,
.01,-.011464,
.010571,-.011064,
.011064,-.010571,
.011464,-.01,
.011759,-.009368,
.011939,-.008695,
.012,-.008,
.012,.008,
.011939,.008695,
.011759,.009368,
.011464,.01,
.011064,.010571,
.010571,.011064,
.01,.011464,
.009368,.011759,
.008695,.011939,
.008,.012,
-.008,.012,
-.008695,.011939,
-.009368,.011759,
-.01,.011464,
-.010571,.011064,
-.011064,.010571,
-.011464,.01,
-.011759,.009368,
-.011939,.008695,
-.012,.008,
0.0*
%
%ADD23MACRO23*%
%AMMACRO37*
4,1,40,.008,.012,
-.008,.012,
-.008695,.011939,
-.009368,.011759,
-.01,.011464,
-.010571,.011064,
-.011064,.010571,
-.011464,.01,
-.011759,.009368,
-.011939,.008695,
-.012,.008,
-.012,-.008,
-.011939,-.008695,
-.011759,-.009368,
-.011464,-.01,
-.011064,-.010571,
-.010571,-.011064,
-.01,-.011464,
-.009368,-.011759,
-.008695,-.011939,
-.008,-.012,
.008,-.012,
.008695,-.011939,
.009368,-.011759,
.01,-.011464,
.010571,-.011064,
.011064,-.010571,
.011464,-.01,
.011759,-.009368,
.011939,-.008695,
.012,-.008,
.012,.008,
.011939,.008695,
.011759,.009368,
.011464,.01,
.011064,.010571,
.010571,.011064,
.01,.011464,
.009368,.011759,
.008695,.011939,
.008,.012,
0.0*
%
%ADD37MACRO37*%
%ADD19O,.024X.032*%
%ADD29R,.05X.065*%
%ADD21R,.045X.055*%
%ADD11C,.217*%
%ADD31O,.086X.048*%
%ADD34R,.272X.272*%
%AMMACRO32*
4,1,40,-.007,-.011,
.007,-.011,
.007695,-.010939,
.008368,-.010759,
.009,-.010464,
.009571,-.010064,
.010064,-.009571,
.010464,-.009,
.010759,-.008368,
.010939,-.007695,
.011,-.007,
.011,.007,
.010939,.007695,
.010759,.008368,
.010464,.009,
.010064,.009571,
.009571,.010064,
.009,.010464,
.008368,.010759,
.007695,.010939,
.007,.011,
-.007,.011,
-.007695,.010939,
-.008368,.010759,
-.009,.010464,
-.009571,.010064,
-.010064,.009571,
-.010464,.009,
-.010759,.008368,
-.010939,.007695,
-.011,.007,
-.011,-.007,
-.010939,-.007695,
-.010759,-.008368,
-.010464,-.009,
-.010064,-.009571,
-.009571,-.010064,
-.009,-.010464,
-.008368,-.010759,
-.007695,-.010939,
-.007,-.011,
0.0*
%
%ADD32MACRO32*%
%AMMACRO26*
4,1,40,-.008,-.012,
.008,-.012,
.008695,-.011939,
.009368,-.011759,
.01,-.011464,
.010571,-.011064,
.011064,-.010571,
.011464,-.01,
.011759,-.009368,
.011939,-.008695,
.012,-.008,
.012,.008,
.011939,.008695,
.011759,.009368,
.011464,.01,
.011064,.010571,
.010571,.011064,
.01,.011464,
.009368,.011759,
.008695,.011939,
.008,.012,
-.008,.012,
-.008695,.011939,
-.009368,.011759,
-.01,.011464,
-.010571,.011064,
-.011064,.010571,
-.011464,.01,
-.011759,.009368,
-.011939,.008695,
-.012,.008,
-.012,-.008,
-.011939,-.008695,
-.011759,-.009368,
-.011464,-.01,
-.011064,-.010571,
-.010571,-.011064,
-.01,-.011464,
-.009368,-.011759,
-.008695,-.011939,
-.008,-.012,
0.0*
%
%ADD26MACRO26*%
%AMMACRO15*
4,1,40,.012,-.008,
.012,.008,
.011939,.008695,
.011759,.009368,
.011464,.01,
.011064,.010571,
.010571,.011064,
.01,.011464,
.009368,.011759,
.008695,.011939,
.008,.012,
-.008,.012,
-.008695,.011939,
-.009368,.011759,
-.01,.011464,
-.010571,.011064,
-.011064,.010571,
-.011464,.01,
-.011759,.009368,
-.011939,.008695,
-.012,.008,
-.012,-.008,
-.011939,-.008695,
-.011759,-.009368,
-.011464,-.01,
-.011064,-.010571,
-.010571,-.011064,
-.01,-.011464,
-.009368,-.011759,
-.008695,-.011939,
-.008,-.012,
.008,-.012,
.008695,-.011939,
.009368,-.011759,
.01,-.011464,
.010571,-.011064,
.011064,-.010571,
.011464,-.01,
.011759,-.009368,
.011939,-.008695,
.012,-.008,
0.0*
%
%ADD15MACRO15*%
%AMMACRO27*
4,1,40,-.011,.007,
-.011,-.007,
-.010939,-.007695,
-.010759,-.008368,
-.010464,-.009,
-.010064,-.009571,
-.009571,-.010064,
-.009,-.010464,
-.008368,-.010759,
-.007695,-.010939,
-.007,-.011,
.007,-.011,
.007695,-.010939,
.008368,-.010759,
.009,-.010464,
.009571,-.010064,
.010064,-.009571,
.010464,-.009,
.010759,-.008368,
.010939,-.007695,
.011,-.007,
.011,.007,
.010939,.007695,
.010759,.008368,
.010464,.009,
.010064,.009571,
.009571,.010064,
.009,.010464,
.008368,.010759,
.007695,.010939,
.007,.011,
-.007,.011,
-.007695,.010939,
-.008368,.010759,
-.009,.010464,
-.009571,.010064,
-.010064,.009571,
-.010464,.009,
-.010759,.008368,
-.010939,.007695,
-.011,.007,
0.0*
%
%ADD27MACRO27*%
%AMMACRO20*
4,1,40,.013,.017,
-.013,.017,
-.013695,.016939,
-.014368,.016759,
-.015,.016464,
-.015571,.016064,
-.016064,.015571,
-.016464,.015,
-.016759,.014368,
-.016939,.013695,
-.017,.013,
-.017,-.013,
-.016939,-.013695,
-.016759,-.014368,
-.016464,-.015,
-.016064,-.015571,
-.015571,-.016064,
-.015,-.016464,
-.014368,-.016759,
-.013695,-.016939,
-.013,-.017,
.013,-.017,
.013695,-.016939,
.014368,-.016759,
.015,-.016464,
.015571,-.016064,
.016064,-.015571,
.016464,-.015,
.016759,-.014368,
.016939,-.013695,
.017,-.013,
.017,.013,
.016939,.013695,
.016759,.014368,
.016464,.015,
.016064,.015571,
.015571,.016064,
.015,.016464,
.014368,.016759,
.013695,.016939,
.013,.017,
0.0*
%
%ADD20MACRO20*%
%AMMACRO33*
4,1,40,-.007,-.011,
.007,-.011,
.007695,-.010939,
.008368,-.010759,
.009,-.010464,
.009571,-.010064,
.010064,-.009571,
.010464,-.009,
.010759,-.008368,
.010939,-.007695,
.011,-.007,
.011,.007,
.010939,.007695,
.010759,.008368,
.010464,.009,
.010064,.009571,
.009571,.010064,
.009,.010464,
.008368,.010759,
.007695,.010939,
.007,.011,
-.007,.011,
-.007695,.010939,
-.008368,.010759,
-.009,.010464,
-.009571,.010064,
-.010064,.009571,
-.010464,.009,
-.010759,.008368,
-.010939,.007695,
-.011,.007,
-.011,-.007,
-.010939,-.007695,
-.010759,-.008368,
-.010464,-.009,
-.010064,-.009571,
-.009571,-.010064,
-.009,-.010464,
-.008368,-.010759,
-.007695,-.010939,
-.007,-.011,
0.0*
%
%ADD33MACRO33*%
%AMMACRO25*
4,1,40,-.008,-.012,
.008,-.012,
.008695,-.011939,
.009368,-.011759,
.01,-.011464,
.010571,-.011064,
.011064,-.010571,
.011464,-.01,
.011759,-.009368,
.011939,-.008695,
.012,-.008,
.012,.008,
.011939,.008695,
.011759,.009368,
.011464,.01,
.011064,.010571,
.010571,.011064,
.01,.011464,
.009368,.011759,
.008695,.011939,
.008,.012,
-.008,.012,
-.008695,.011939,
-.009368,.011759,
-.01,.011464,
-.010571,.011064,
-.011064,.010571,
-.011464,.01,
-.011759,.009368,
-.011939,.008695,
-.012,.008,
-.012,-.008,
-.011939,-.008695,
-.011759,-.009368,
-.011464,-.01,
-.011064,-.010571,
-.010571,-.011064,
-.01,-.011464,
-.009368,-.011759,
-.008695,-.011939,
-.008,-.012,
0.0*
%
%ADD25MACRO25*%
%AMMACRO14*
4,1,40,.012,-.008,
.012,.008,
.011939,.008695,
.011759,.009368,
.011464,.01,
.011064,.010571,
.010571,.011064,
.01,.011464,
.009368,.011759,
.008695,.011939,
.008,.012,
-.008,.012,
-.008695,.011939,
-.009368,.011759,
-.01,.011464,
-.010571,.011064,
-.011064,.010571,
-.011464,.01,
-.011759,.009368,
-.011939,.008695,
-.012,.008,
-.012,-.008,
-.011939,-.008695,
-.011759,-.009368,
-.011464,-.01,
-.011064,-.010571,
-.010571,-.011064,
-.01,-.011464,
-.009368,-.011759,
-.008695,-.011939,
-.008,-.012,
.008,-.012,
.008695,-.011939,
.009368,-.011759,
.01,-.011464,
.010571,-.011064,
.011064,-.010571,
.011464,-.01,
.011759,-.009368,
.011939,-.008695,
.012,-.008,
0.0*
%
%ADD14MACRO14*%
%AMMACRO28*
4,1,40,-.011,.007,
-.011,-.007,
-.010939,-.007695,
-.010759,-.008368,
-.010464,-.009,
-.010064,-.009571,
-.009571,-.010064,
-.009,-.010464,
-.008368,-.010759,
-.007695,-.010939,
-.007,-.011,
.007,-.011,
.007695,-.010939,
.008368,-.010759,
.009,-.010464,
.009571,-.010064,
.010064,-.009571,
.010464,-.009,
.010759,-.008368,
.010939,-.007695,
.011,-.007,
.011,.007,
.010939,.007695,
.010759,.008368,
.010464,.009,
.010064,.009571,
.009571,.010064,
.009,.010464,
.008368,.010759,
.007695,.010939,
.007,.011,
-.007,.011,
-.007695,.010939,
-.008368,.010759,
-.009,.010464,
-.009571,.010064,
-.010064,.009571,
-.010464,.009,
-.010759,.008368,
-.010939,.007695,
-.011,.007,
0.0*
%
%ADD28MACRO28*%
%ADD40C,.006*%
%ADD41C,.0072*%
%ADD42C,.0084*%
%ADD46R,.008X.019*%
%ADD43C,.09204*%
%ADD47C,.09504*%
%ADD44C,.11004*%
%ADD48C,.11704*%
%ADD45R,.008X.008*%
%ADD49R,.29604X.29604*%
G75*
%LPD*%
G75*
G36*
G01X59897Y86182D02*
X47057D01*
X45885Y85010D01*
Y74258D01*
X46734Y73409D01*
X54000D01*
X55500Y71909D01*
Y4300D01*
X54204Y3004D01*
X3937D01*
G02X3004Y3937I0J933D01*
G01Y87402D01*
G02X3937Y88335I933J0D01*
G01X188079D01*
X189368Y87046D01*
Y81500D01*
X187498Y79630D01*
X177071D01*
X168345Y70904D01*
X65329D01*
X63517Y72716D01*
Y84323D01*
X61658Y86182D01*
X60889D01*
X60864Y86187D01*
G03X59922I-471J-2253D01*
G01X59897Y86182D01*
G37*
G36*
G01X47903Y74818D02*
X47121Y75600D01*
Y83903D01*
X48198Y84980D01*
X61028D01*
X61677Y84332D01*
Y75760D01*
X60735Y74818D01*
X47903D01*
G37*
G36*
G01X175254Y12185D02*
X175079Y12321D01*
G03X171603Y12402I-1792J-2282D01*
G01X171431Y12279D01*
X170187Y13523D01*
Y29310D01*
X171600Y30723D01*
Y30785D01*
X175814Y34998D01*
X188432D01*
X188700Y34731D01*
Y29074D01*
X188200Y28574D01*
X183857D01*
X183786Y28503D01*
X183769D01*
X175830Y20564D01*
Y12761D01*
X175254Y12185D01*
G37*
G36*
G01X178216Y12940D02*
G02X177704Y13440I-12J500D01*
G01Y19074D01*
X185106Y26476D01*
X189000D01*
X190800Y28276D01*
Y34700D01*
X196351Y40251D01*
X201531D01*
X201875Y39907D01*
Y39830D01*
G03X201872Y39741I1599J-98D01*
G01Y38141D01*
G03X201875Y38058I1601J16D01*
G01Y23864D01*
X196019Y18008D01*
X191657D01*
X185539Y11890D01*
X185362Y12068D01*
X185361Y12069D01*
G03X181154Y12007I-2074J-2030D01*
G02X180420I-367J339D01*
G03X178216Y12940I-2133J-1968D01*
G37*
G36*
G01X172262Y57243D02*
G02X171586Y57711I-176J468D01*
G01Y59074D01*
X170162Y60498D01*
Y67313D01*
X179954Y77105D01*
X184989D01*
Y69511D01*
X175026Y59548D01*
Y57696D01*
G02X174344Y57231I-500J0D01*
G03X172262Y57243I-1057J-2703D01*
G37*
G36*
G01X181154Y56496D02*
G02X180420I-367J339D01*
G03X177531Y57330I-2133J-1968D01*
G02X176901Y57798I-130J482D01*
G03X176580Y58883I-2201J-61D01*
G01X176543Y58943D01*
Y59366D01*
X186190Y69013D01*
Y69088D01*
X186301Y69199D01*
Y76301D01*
X193500Y83500D01*
X198015D01*
Y68887D01*
X185524Y56396D01*
X185346Y56573D01*
G03X181154Y56496I-2059J-2045D01*
G37*
G36*
G01X222670Y35291D02*
Y29441D01*
X217404Y24175D01*
X216329D01*
X207326Y15172D01*
X207291Y15154D01*
G03X206324Y14187I996J-1963D01*
G01X206306Y14152D01*
X205346Y13192D01*
Y13063D01*
G02X204617Y12618I-500J0D01*
G03X201154Y12007I-1330J-2579D01*
G02X200420I-367J339D01*
G03X199785Y12524I-2131J-1969D01*
G01Y14837D01*
X213820Y28872D01*
X215621D01*
X218155Y31406D01*
Y33842D01*
X220034Y35721D01*
X222240D01*
X222670Y35291D01*
G37*
G36*
G01X203076Y30855D02*
Y40180D01*
X203654Y40757D01*
X215488D01*
X216038Y40207D01*
Y38405D01*
X215536Y37903D01*
X213299D01*
X212522Y37126D01*
Y34806D01*
X212108Y34392D01*
X211996Y34399D01*
G03X211900Y34402I-98J-1599D01*
G01X210300D01*
G03X210057Y34383I3J-1602D01*
G01X210038Y34380D01*
X208911D01*
X208274Y33743D01*
Y30617D01*
X208173Y30516D01*
X203415D01*
X203076Y30855D01*
G37*
G36*
G01X206589Y51344D02*
G02X207265Y51812I500J0D01*
G03X210420Y52560I1022J2716D01*
G02X211154I367J-339D01*
G03Y56496I2133J1968D01*
G02X210420I-367J339D01*
G03X208386Y57428I-2132J-1968D01*
G02X208050Y58282I17J500D01*
G01X220174Y70406D01*
Y78138D01*
X220182Y78168D01*
G03X220232Y78564I-1552J397D01*
G01Y80164D01*
G03X220182Y80560I-1602J-1D01*
G01X220174Y80590D01*
Y87149D01*
X221889Y88864D01*
X230948D01*
X231398Y88414D01*
Y71428D01*
X221138Y61168D01*
Y57974D01*
X231276Y47836D01*
X235022D01*
X236706Y46152D01*
Y28668D01*
X232816Y24778D01*
X228861D01*
X218695Y14612D01*
Y9298D01*
X217736Y8339D01*
X216470D01*
G02X216002Y9015I0J500D01*
G03X211154Y12007I-2715J1024D01*
G02X210420I-367J339D01*
G03X208094Y12935I-2133J-1968D01*
G02X207707Y13787I-33J499D01*
G01X216382Y22462D01*
X217390D01*
X224625Y29697D01*
Y40522D01*
X224408Y40740D01*
Y41500D01*
G03X221680Y43638I-2202J0D01*
G01X221543Y43604D01*
X218250Y46897D01*
X210204D01*
X206589Y50512D01*
Y51344D01*
G37*
G36*
G01X205346Y57551D02*
G02X204617Y57107I-500J1D01*
G03X201154Y56496I-1330J-2579D01*
G02X200420I-367J339D01*
G03X199785Y57013I-2131J-1969D01*
G01Y59326D01*
X213820Y73361D01*
Y75790D01*
X214698Y76668D01*
X217968D01*
X218295Y76341D01*
Y71160D01*
X205346Y58211D01*
Y57551D01*
G37*
G36*
G01X204131Y74154D02*
X199677D01*
X199288Y74543D01*
Y86288D01*
X200500Y87500D01*
X208350D01*
X208850Y87000D01*
Y78198D01*
X207965Y77313D01*
X205187D01*
X204660Y76786D01*
Y74683D01*
X204131Y74154D01*
G37*
G36*
G01X254392Y7604D02*
X241873D01*
X240747Y8730D01*
Y62791D01*
X236390Y67148D01*
Y88453D01*
X236616Y88679D01*
X274819D01*
X276775Y86723D01*
Y65000D01*
X267289Y55514D01*
X256802D01*
X255353Y54065D01*
Y8565D01*
X254392Y7604D01*
G37*
G36*
G01X272665Y39134D02*
X271573Y40226D01*
Y57273D01*
X272200Y57900D01*
X286300D01*
X287800Y56400D01*
Y40000D01*
X285994Y38194D01*
X275469D01*
G03X272814Y39187I-1918J-1082D01*
G01X272665Y39134D01*
G37*
G36*
G01X267686Y36934D02*
X257533D01*
X256702Y37765D01*
Y52710D01*
X257759Y53767D01*
X267648D01*
X268516Y52899D01*
Y37764D01*
X267686Y36934D01*
G37*
G36*
G01X477308Y78001D02*
G02X476810Y78551I0J500D01*
G03X476493Y80680I-3661J543D01*
G03X472304Y82699I-3345J-1585D01*
G01X472276Y82692D01*
X471108D01*
X468946Y84854D01*
Y94488D01*
G03X462008Y101426I-6938J0D01*
G01X381640D01*
Y101429D01*
X379921D01*
G03X372980Y94488I0J-6941D01*
G01Y30512D01*
X372983Y30515D01*
Y3937D01*
G02X372047Y3001I-936J0D01*
G01X287599D01*
X286674Y3926D01*
Y15326D01*
X295175Y23828D01*
X309000D01*
X318728Y14100D01*
X324611D01*
G03X324789I89J2200D01*
G01X326500D01*
X329349Y16949D01*
X337152D01*
X337195Y16992D01*
G02X338048Y16639I353J-354D01*
G01Y16390D01*
X337991Y16321D01*
G03X337453Y14136I2009J-1653D01*
G03X339328Y12153I2547J531D01*
G03X341702Y16636I672J2514D01*
G01Y18366D01*
G03X342002Y19299I-1302J933D01*
G01Y20700D01*
G03X341841Y21400I-1602J0D01*
G01X341763Y21560D01*
X343065Y22862D01*
X349870D01*
X351681Y21051D01*
X363519D01*
X367984Y25516D01*
Y94488D01*
G02X371771Y103210I11938J0D01*
G01X391144Y122583D01*
Y128567D01*
X395171Y132594D01*
X514203D01*
X520412Y138803D01*
X520545Y138684D01*
G03X528853Y146909I3960J4309D01*
G01X528695Y147086D01*
X530866Y149257D01*
Y212075D01*
X526597Y216344D01*
X515969D01*
X510694Y221619D01*
Y225763D01*
X507895Y228562D01*
X490414D01*
X485756Y233220D01*
X464157D01*
X456539Y225602D01*
Y214097D01*
X451868Y209426D01*
X376809D01*
X366883Y199500D01*
X346000D01*
X343000Y202500D01*
Y202515D01*
X341702Y203814D01*
Y204998D01*
X340498Y206202D01*
X339314D01*
X338996Y206519D01*
X324735D01*
X314840Y216414D01*
X307000D01*
X305500Y214914D01*
Y211199D01*
X305298Y210998D01*
Y188002D01*
X305500Y187801D01*
Y179500D01*
X294400Y168400D01*
Y166299D01*
X294398Y166298D01*
Y166199D01*
X294387Y166127D01*
X294380Y166106D01*
G03X294298Y165602I1510J-504D01*
G01Y163998D01*
G03X294384Y163482I1592J0D01*
G01X294398Y163442D01*
Y143302D01*
X294400Y143301D01*
Y140600D01*
X292738Y138938D01*
X277857D01*
X276626Y140169D01*
Y171083D01*
X276623D01*
Y252756D01*
G02X277559Y253692I936J0D01*
G01X561024D01*
G02X561960Y252756I0J-936D01*
G01Y3937D01*
G02X561024Y3001I-936J0D01*
G01X537402D01*
G02X536466Y3937I0J936D01*
G01Y71063D01*
G03X534699Y75689I-6939J0D01*
G02X534717Y76375I372J333D01*
G03X535136Y81354I-2512J2719D01*
G03X532490Y82785I-2932J-2259D01*
G03X528544Y78551I-285J-3691D01*
G02X528046Y78001I-498J-50D01*
G01X477308D01*
G37*
G36*
G01X281027Y118487D02*
G02X281015Y119195I347J360D01*
G03X278602Y122769I-1578J1536D01*
G02X277913Y123231I-189J463D01*
G01Y135179D01*
X279121Y136387D01*
X305302D01*
X306824Y134865D01*
Y131294D01*
X303604Y128074D01*
X290500D01*
X288500Y126074D01*
Y69809D01*
X287198Y68507D01*
Y60544D01*
X286098Y59444D01*
X279144D01*
X278291Y60297D01*
Y89171D01*
X277913Y89549D01*
Y93307D01*
X281202Y96595D01*
Y115502D01*
G03X281027Y118487I-1702J1398D01*
G37*
G36*
G01X296400Y143000D02*
X295602Y143798D01*
Y144044D01*
X295600D01*
Y165556D01*
X295602D01*
Y165802D01*
X295900Y166100D01*
X313237D01*
X313434Y165903D01*
X326862D01*
X327850Y164914D01*
Y159512D01*
X324560Y156222D01*
Y151750D01*
X322559Y149749D01*
X322434Y149768D01*
G03X319602Y148100I-392J-2572D01*
G01X319542Y147937D01*
X309637D01*
X308932Y147232D01*
X308869Y147214D01*
G03X307286Y145631I631J-2214D01*
G01X307268Y145568D01*
X304700Y143000D01*
X303791D01*
G03X303609I-91J-2300D01*
G01X296400D01*
G37*
G36*
G01X332903Y39005D02*
X333733Y38175D01*
Y33197D01*
X332765Y32229D01*
X330035D01*
X327822Y34442D01*
X319248D01*
X318556Y35134D01*
Y43613D01*
X318951Y44008D01*
X325496D01*
X325688Y43816D01*
Y40758D01*
X327441Y39005D01*
X332903D01*
G37*
G36*
G01X318364Y45284D02*
X317762Y45886D01*
Y57121D01*
X319364Y58722D01*
X331684D01*
X332213Y58193D01*
Y55341D01*
X331953Y55081D01*
X326748D01*
X326318Y54652D01*
X325869Y54203D01*
Y45528D01*
X325625Y45284D01*
X318364D01*
G37*
G36*
G01X324447Y195948D02*
Y191192D01*
X320257Y187002D01*
X307998D01*
X306702Y188298D01*
Y188300D01*
X306500Y188501D01*
Y204637D01*
X306514Y204677D01*
G03X306602Y205200I-1514J524D01*
G01Y206800D01*
G03X306514Y207323I-1602J-1D01*
G01X306500Y207363D01*
Y208137D01*
X306514Y208177D01*
G03X306602Y208700I-1514J524D01*
G01Y210300D01*
G03X306593Y210462I-1602J-8D01*
G01X306581Y210580D01*
X306702Y210700D01*
Y210702D01*
X307000Y211000D01*
X313967D01*
X313992Y210995D01*
G03X314916I462J2255D01*
G01X314941Y211000D01*
X317506D01*
X325888Y202618D01*
Y197390D01*
X324447Y195948D01*
G37*
G36*
G01X343388Y40000D02*
X342153Y41235D01*
Y54181D01*
X342687Y54715D01*
X362750D01*
X363000Y54465D01*
Y41000D01*
X362081Y40081D01*
X361963Y40093D01*
G03X361800Y40102I-170J-1593D01*
G01X360200D01*
G03X359677Y40014I1J-1602D01*
G01X359637Y40000D01*
X358263D01*
X358223Y40014D01*
G03X357700Y40102I-524J-1514D01*
G01X356300D01*
G03X355777Y40014I1J-1602D01*
G01X355737Y40000D01*
X343388D01*
G37*
G36*
G01X327947Y40345D02*
X327320Y40972D01*
Y53127D01*
X327995Y53802D01*
X338680D01*
X339322Y53160D01*
Y41253D01*
X338414Y40345D01*
X327947D01*
G37*
G36*
G01X343594Y153484D02*
X342556Y152446D01*
X326369D01*
X325869Y152946D01*
Y155777D01*
X329052Y158960D01*
Y170309D01*
X330560Y171817D01*
X343008D01*
X343594Y171231D01*
Y153484D01*
G37*
G36*
G01X340500Y192500D02*
X339500Y191500D01*
X326500D01*
X326000Y192000D01*
Y195386D01*
X327090Y196476D01*
Y203641D01*
X328449Y205000D01*
X340000D01*
X340500Y204500D01*
Y192500D01*
G37*
G36*
G01X485521Y152072D02*
X477632D01*
X468854Y143294D01*
X468788Y143277D01*
G03X467198Y141687I543J-2133D01*
G01X467181Y141621D01*
X466386Y140826D01*
Y140576D01*
G02X465992Y140371I-250J0D01*
G03X462592Y140315I-1661J-2379D01*
G02X461792Y140715I-300J400D01*
G01Y145407D01*
X475661Y159276D01*
X476490Y160104D01*
X489892D01*
X490354Y159642D01*
Y156905D01*
X485521Y152072D01*
G37*
G36*
G01X472198Y139960D02*
G02X471464I-367J339D01*
G03X469356Y140894I-2133J-1968D01*
G02X469006Y141747I4J500D01*
G01X478130Y150871D01*
X486019D01*
X490714Y155566D01*
X490747Y155584D01*
G03X491416Y156253I-747J1416D01*
G01X491434Y156286D01*
X492593Y157445D01*
Y179334D01*
X490210Y181717D01*
X490192Y181780D01*
G03X485918Y186054I-5940J-1666D01*
G01X485855Y186072D01*
X485000Y186927D01*
X471428D01*
X467557Y190798D01*
Y200586D01*
G02X468244Y201049I500J-1D01*
G03X471464Y201772I1087J2691D01*
G02X472198I367J-339D01*
G03X476381Y201686I2133J1968D01*
G01X476558Y201862D01*
X482642Y195778D01*
X489943D01*
X502360Y183360D01*
Y170183D01*
X500072Y167895D01*
Y155834D01*
X487502Y143264D01*
X479432D01*
X476296Y140128D01*
G03X472198Y139960I-1965J-2136D01*
G37*
G36*
G01X460676Y206311D02*
Y225600D01*
X461406Y226330D01*
X465261D01*
X465898Y225693D01*
Y206970D01*
G02X465241Y206496I-500J1D01*
G03X462198Y205708I-910J-2756D01*
G02X461464I-367J339D01*
G03X460676Y206311I-2132J-1969D01*
G37*
G36*
G01X471464Y205708D02*
G03X468244Y206431I-2133J-1968D01*
G02X467557Y206894I-187J464D01*
G01Y222621D01*
X467403Y222775D01*
Y226051D01*
X467776Y226424D01*
X472461D01*
X472994Y225891D01*
Y222400D01*
X476100Y219294D01*
Y206896D01*
G02X475414Y206433I-500J1D01*
G03X472198Y205708I-1083J-2693D01*
G02X471464I-367J339D01*
G37*
G36*
G01X496303Y140121D02*
G03X493317Y140711I-1972J-2129D01*
G02X492642Y141179I-175J468D01*
G01Y141455D01*
X509907Y158721D01*
Y159920D01*
X510244Y160257D01*
X513124D01*
X513443Y159938D01*
Y156356D01*
X512008Y154921D01*
X511997D01*
X503224Y146148D01*
X503072D01*
X500278Y143354D01*
X500210Y143337D01*
G03X498729Y142088I534J-2136D01*
G01X498507Y141583D01*
X497765Y140841D01*
X497703D01*
X496996Y140134D01*
G02X496303Y140121I-353J354D01*
G37*
G36*
G01X512293Y142794D02*
X507980Y138481D01*
G02X507143Y138711I-353J354D01*
G03X502198Y139960I-2812J-719D01*
G02X501464I-367J339D01*
G03X500498Y140649I-2133J-1968D01*
G02X500346Y141460I202J458D01*
G01X515610Y156724D01*
Y179334D01*
X497700Y197244D01*
Y200532D01*
G02X498366Y201003I500J-1D01*
G03X501464Y201772I965J2737D01*
G02X502198I367J-339D01*
G03Y205708I2133J1968D01*
G02X501464I-367J339D01*
G03X498366Y206477I-2133J-1968D01*
G02X497700Y206948I-166J472D01*
G01Y216600D01*
X495600Y218700D01*
Y225456D01*
X496187Y226043D01*
X506315D01*
X506700Y225658D01*
Y218641D01*
X511728Y213613D01*
Y202827D01*
X526618Y187937D01*
Y157119D01*
X516339Y146840D01*
X516232Y146842D01*
G03X512291Y142901I-91J-3850D01*
G01X512293Y142794D01*
G37*
G36*
G01X496162Y206871D02*
G02X495466Y206411I-500J0D01*
G03X492198Y205708I-1135J-2671D01*
G02X491464I-367J339D01*
G03X490974Y206132I-2132J-1969D01*
G01X490955Y206145D01*
X489050Y208050D01*
Y210650D01*
X489000Y210700D01*
Y225727D01*
X489368Y226095D01*
X493156D01*
X493600Y225651D01*
Y215700D01*
X496162Y213138D01*
Y206871D01*
G37*
%LPC*%
G75*
G36*
G01X350218Y8481D02*
G03X349672Y8088I-57J-497D01*
G02X347682Y10855I-2251J480D01*
G03X348228Y11248I57J497D01*
G02X350218Y8481I2251J-480D01*
G37*
G36*
G01X417106Y214952D02*
G02X413956I-1575J1813D01*
G02X409980Y216765I-1575J1813D01*
G01Y217565D01*
G02X413956Y219378I2401J0D01*
G02X417106I1575J-1813D01*
G02X420256I1575J-1813D01*
G02X423406I1575J-1813D01*
G02X426556I1575J-1813D01*
G02X429706I1575J-1813D01*
G02X433682Y217565I1575J-1813D01*
G01Y216765D01*
G02X429706Y214952I-2401J0D01*
G02X426556I-1575J1813D01*
G02X423406I-1575J1813D01*
G02X420256I-1575J1813D01*
G02X417106I-1575J1813D01*
G37*
G36*
G01X322546Y42029D02*
X322823Y42024D01*
X323623D01*
Y41224D01*
X322823D01*
X322546Y41229D01*
X321746D01*
Y42029D01*
X322546D01*
G37*
G36*
G01Y48029D02*
X322823Y48024D01*
X323623D01*
Y47224D01*
X322823D01*
X322546Y47229D01*
X321746D01*
Y48029D01*
X322546D01*
G37*
G54D46*
X43500Y77750D03*
X49500D03*
X303000Y207750D03*
X309000D03*
G54D43*
X32739Y30456D03*
G54D47*
X520394Y86811D03*
X508583D03*
X496771D03*
X484960D03*
G54D44*
X17715Y44095D03*
X552795Y40157D03*
X525590Y240944D03*
G54D48*
X359156Y208740D03*
G54D45*
X43500Y80700D03*
Y74800D03*
X49500Y80700D03*
X185200Y30400D03*
Y33800D03*
X194200Y30400D03*
Y33800D03*
X199474Y37741D03*
X181000Y73300D03*
X190000Y76700D03*
Y73300D03*
X195630Y80664D03*
X219220Y32197D03*
X209900Y36800D03*
X205474Y37741D03*
X222630Y80564D03*
Y78164D03*
X223894Y76662D03*
Y73262D03*
X226956Y39499D03*
Y37099D03*
X228220Y35597D03*
Y32197D03*
X214894Y73262D03*
X206300Y79500D03*
X201630Y80664D03*
Y83064D03*
X303000Y204800D03*
Y210700D03*
X291900Y166000D03*
Y163600D03*
X304700Y134600D03*
Y132400D03*
X297900Y163600D03*
X324052Y36595D03*
X326252D03*
X319865Y36600D03*
X322065D03*
X319746Y41629D03*
Y47629D03*
X309000Y204800D03*
X355900Y42300D03*
X358100D03*
X359800Y42500D03*
X332351Y154840D03*
X329951D03*
X328251Y154640D03*
X487000Y156600D03*
X496000Y160000D03*
Y156600D03*
X462335Y222563D03*
X471335D03*
X510000Y156800D03*
X499146Y222352D03*
X519000Y160200D03*
Y156800D03*
X490146Y222352D03*
G54D49*
X332000Y234500D03*
%LPD*%
G75*
G54D10*
G01X188287Y10039D02*
X184882Y6634D01*
X85288D01*
X80156Y11766D01*
Y27240D01*
X69900Y37496D01*
Y45892D01*
X60928Y54864D01*
Y64173D01*
G01X193287Y10039D02*
X186861Y3613D01*
X84036D01*
X77135Y10514D01*
Y26653D01*
X74635Y29153D01*
G01X188287Y54528D02*
Y52242D01*
X187286Y51241D01*
X87262D01*
X76804Y61699D01*
G01X193287Y54528D02*
Y50802D01*
X195000Y49089D01*
Y41572D01*
X190128Y36700D01*
X75100D01*
G01X211100Y32050D02*
Y29809D01*
X197240Y15949D01*
X194197D01*
X188287Y10039D01*
G01X207500Y74750D02*
X188287Y55537D01*
Y54528D01*
G01X211500Y74750D02*
X207500D01*
G01X208000Y90000D02*
X209500Y91500D01*
X273700D01*
X279500Y97300D01*
Y116900D01*
G01X204500Y90000D02*
X208200Y93700D01*
X272788D01*
X277200Y98112D01*
Y118494D01*
X279437Y120731D01*
G01X214956Y32049D02*
X214955Y32050D01*
X211100D01*
G01X324700Y16300D02*
X319301D01*
X309609Y25992D01*
X284671D01*
X273551Y37112D01*
G01X309250Y133500D02*
Y127439D01*
G01X325250Y142000D02*
X321250D01*
G01D02*
Y146404D01*
X322042Y147196D01*
G01X339750Y20000D02*
X340000Y19750D01*
Y14667D01*
G01X325152Y32045D02*
X327069Y30128D01*
X334590D01*
X335298Y29420D01*
Y26216D01*
X325382Y16300D01*
X324700D01*
G01X336238Y148951D02*
X335099Y150090D01*
X331151D01*
G01X327151D02*
Y146579D01*
X328750Y144980D01*
Y142000D01*
G01X331151Y150090D02*
X327151D01*
G01X356750Y29500D02*
X352250D01*
G01D02*
Y33543D01*
X351040Y34753D01*
G01X360250Y29500D02*
Y25278D01*
X358900Y23928D01*
G01X357000Y37750D02*
Y34652D01*
X360250Y31402D01*
Y29500D01*
G01X364750Y37750D02*
X361000D01*
G01D02*
X357000D01*
G01X502868Y159536D02*
Y156118D01*
X488112Y141362D01*
X482701D01*
X479331Y137992D01*
G01X479900Y223750D02*
X479331Y223181D01*
Y203740D01*
G01X483700Y223750D02*
X479900D01*
G01X506868Y159536D02*
X502868D01*
X-14755Y415558D03*
X-12454Y45507D03*
X17715Y44095D03*
X29461Y718854D03*
X141466Y655356D03*
X225097Y15039D03*
Y59528D03*
X312657Y66142D03*
Y107716D03*
X395935Y76695D03*
X473149Y79094D03*
X508569Y15093D03*
X516141Y142992D03*
Y208740D03*
X525590Y240944D03*
X552795Y40157D03*
X532205Y79094D03*
X554126Y315939D03*
Y685624D03*
G54D20*
X182700Y75000D03*
X186900Y32100D03*
X220920Y33897D03*
X216594Y74962D03*
X464035Y224263D03*
X488700Y158300D03*
X491846Y224052D03*
X511700Y158500D03*
G54D11*
X15748Y15827D03*
Y67008D03*
X303150Y13780D03*
Y242913D03*
X551181Y13780D03*
Y242913D03*
G54D21*
X198356Y33399D03*
X205956D03*
X194830Y76364D03*
X202430D03*
X266292Y48559D03*
X273892D03*
X309800Y192500D03*
X302200D03*
X322966Y199919D03*
X309800Y200500D03*
X302200D03*
X337012Y44327D03*
X344612D03*
X324686Y162130D03*
X332286D03*
X330566Y199919D03*
G54D30*
X267148Y39395D03*
X271238Y67208D03*
X322100Y26600D03*
X309250Y127439D03*
X322042Y147196D03*
X310500Y152000D03*
X321777Y191293D03*
X310500Y184328D03*
X340000Y14667D03*
X336921Y51884D03*
X351040Y34753D03*
X358900Y23928D03*
G54D12*
X5500Y48299D03*
X7960Y85839D03*
X42701Y5500D03*
X48316Y32530D03*
X44316D03*
Y28681D03*
X48316D03*
X44278Y24717D03*
X48278D03*
X49374Y56390D03*
X45374D03*
X45336Y52426D03*
X49336D03*
X41000Y79500D03*
Y75500D03*
X37000Y79500D03*
Y75500D03*
X49374Y60239D03*
X45374D03*
X27960Y85839D03*
X63713Y48425D03*
X65006Y43434D03*
X60469Y79819D03*
X67960Y85839D03*
X56667Y83351D03*
X60393Y83934D03*
X52667Y83351D03*
X87960Y85839D03*
X107960D03*
X127960D03*
X147960D03*
X167960D03*
X207675Y38907D03*
X204000Y82000D03*
X208000D03*
Y86000D03*
X204000D03*
X187960Y85839D03*
X214906Y39494D03*
X211337Y38963D03*
X242500Y27000D03*
X246500D03*
X243000Y47500D03*
X247000D03*
X244727Y76591D03*
X244870Y80370D03*
X248866Y76464D03*
X248811Y80272D03*
X261719Y52314D03*
X261774Y48506D03*
X261840Y42259D03*
X261924Y38480D03*
X258240Y42259D03*
X258174Y48506D03*
X258119Y52314D03*
X258324Y38480D03*
X281221Y33971D03*
X286638Y33917D03*
X282148Y51376D03*
X282093Y55184D03*
X278462Y51437D03*
X278407Y55245D03*
X281964Y47752D03*
X278278Y47813D03*
X284292Y61505D03*
X280555Y61542D03*
X284798Y149063D03*
X299300Y144500D03*
X284905Y160541D03*
X284940Y156881D03*
X284798Y152687D03*
X289800Y165000D03*
X300000Y164900D03*
X297698Y191563D03*
Y195187D03*
X279122Y174213D03*
Y194213D03*
X297840Y199381D03*
X297805Y203041D03*
X279122Y214213D03*
Y234213D03*
X282142Y251193D03*
X322701Y5500D03*
X321373Y56703D03*
X303700Y140700D03*
X315048Y133300D03*
X302000Y133500D03*
X301913Y129821D03*
X303000Y144400D03*
X309500Y145000D03*
X303600Y164800D03*
X320332Y160022D03*
X316332D03*
Y164522D03*
X320332D03*
X316332Y155668D03*
X320332D03*
X316438Y151436D03*
X320438D03*
X318500Y193500D03*
X314500D03*
X318500Y188500D03*
X314500D03*
X300754Y205956D03*
X304000Y213000D03*
X314454Y213250D03*
X314500Y203500D03*
X318500D03*
Y198500D03*
X314500D03*
X322142Y251193D03*
X332666Y27700D03*
X332778Y20000D03*
X328508Y41629D03*
X328424Y45408D03*
X332508Y41629D03*
X332424Y45408D03*
X332565Y49028D03*
X332614Y52663D03*
X328565Y49028D03*
X328614Y52663D03*
X336698Y154738D03*
X340698D03*
X340779Y158381D03*
Y162024D03*
X336779D03*
Y158381D03*
X340779Y165718D03*
X336779D03*
X326423Y183632D03*
X332000Y183500D03*
X339000Y193500D03*
X335000D03*
X326000Y217500D03*
X335000Y203500D03*
X339000D03*
Y198500D03*
X335000D03*
X342142Y251193D03*
X357672Y4602D03*
X347421Y8568D03*
X350479Y10768D03*
X345690Y20300D03*
X353229Y52810D03*
X349229D03*
X353095Y45538D03*
X353094Y49157D03*
X352971Y41813D03*
X349095Y45538D03*
X349094Y49157D03*
X348971Y41813D03*
X364750Y37750D03*
X354580Y102351D03*
X350569Y102263D03*
X358824Y108849D03*
X352501Y105640D03*
X350827Y108976D03*
X348696Y105396D03*
X356501Y105640D03*
X354827Y108976D03*
X362142Y251193D03*
X382142D03*
X402142D03*
X422142D03*
X442142D03*
X471445Y93346D03*
X476600Y227250D03*
X480101Y230616D03*
X462142Y251193D03*
X502868Y166448D03*
X483700Y230522D03*
X502142Y251193D03*
X482142D03*
X519980Y226295D03*
X523642Y226351D03*
X520017Y230070D03*
X523642Y230014D03*
X522142Y251193D03*
X538965Y41992D03*
Y61992D03*
X559461Y68512D03*
Y88512D03*
Y108512D03*
Y148512D03*
Y128512D03*
Y168512D03*
Y188512D03*
Y208512D03*
G54D40*
G01X-116181Y-215185D02*
Y-232685D01*
G01X-121203Y-215185D02*
X-111159D01*
G01X-103048Y-232685D02*
Y-215185D01*
X-97808D01*
X-96061Y-216060D01*
X-94751Y-218102D01*
X-94314Y-220435D01*
X-94751Y-222768D01*
X-95843Y-224518D01*
X-97808Y-225394D01*
X-103048D01*
G01X-58878Y-216644D02*
X-60188Y-215768D01*
X-61716Y-215185D01*
X-63463D01*
X-65428Y-216060D01*
X-66956Y-217518D01*
X-68048Y-219269D01*
X-68921Y-222185D01*
X-69140Y-224810D01*
X-68703Y-227435D01*
X-68048Y-229185D01*
X-66738Y-230935D01*
X-65209Y-232102D01*
X-63681Y-232685D01*
X-62153D01*
X-60624Y-232102D01*
X-59314Y-231227D01*
X-58222Y-230061D01*
G01X-49893Y-232685D02*
Y-215185D01*
G01Y-223643D02*
X-48801Y-222185D01*
X-47709Y-221310D01*
X-45963Y-221019D01*
X-44653Y-221310D01*
X-43124Y-222477D01*
X-42469Y-224227D01*
Y-232685D01*
G01X-24751D02*
Y-221019D01*
G01Y-223060D02*
X-25624Y-221894D01*
X-26935Y-221310D01*
X-28463Y-221019D01*
X-29991Y-221602D01*
X-31301Y-222768D01*
X-32175Y-224518D01*
X-32611Y-226852D01*
X-32175Y-229185D01*
X-31301Y-230935D01*
X-29991Y-232102D01*
X-28463Y-232685D01*
X-26935Y-232393D01*
X-25624Y-231519D01*
X-24751Y-230352D01*
G01X-14893Y-232685D02*
Y-221019D01*
G01Y-223935D02*
X-14019Y-222477D01*
X-12709Y-221310D01*
X-10963Y-221019D01*
X-9435Y-221310D01*
X-8124Y-222477D01*
X-7469Y-224518D01*
Y-232685D01*
G01X2607D02*
Y-221019D01*
G01Y-223935D02*
X3481Y-222477D01*
X4791Y-221310D01*
X6537Y-221019D01*
X8065Y-221310D01*
X9376Y-222477D01*
X10031Y-224518D01*
Y-232685D01*
G01X20544Y-224810D02*
X27531D01*
X26876Y-222768D01*
X25784Y-221602D01*
X24256Y-221019D01*
X22727Y-221310D01*
X21417Y-222185D01*
X20544Y-224227D01*
X20107Y-225977D01*
Y-227727D01*
X20544Y-229477D01*
X21636Y-231227D01*
X22946Y-232393D01*
X24474Y-232685D01*
X26002Y-232102D01*
X27531Y-230352D01*
G01X41319Y-232685D02*
Y-215185D01*
G01X71734Y-232685D02*
Y-215185D01*
G01X80904D02*
Y-232685D01*
G01Y-223935D02*
X71734D01*
G01X89016Y-232685D02*
Y-215185D01*
X93382D01*
X95129Y-216060D01*
X96439Y-217227D01*
X97531Y-218976D01*
X98404Y-221019D01*
X98622Y-223935D01*
X98404Y-226852D01*
X97531Y-228894D01*
X96439Y-230644D01*
X95129Y-231810D01*
X93382Y-232685D01*
X89016D01*
G01X106516D02*
Y-215185D01*
X110882D01*
X112629Y-216060D01*
X113939Y-217227D01*
X115031Y-218976D01*
X115904Y-221019D01*
X116122Y-223935D01*
X115904Y-226852D01*
X115031Y-228894D01*
X113939Y-230644D01*
X112629Y-231810D01*
X110882Y-232685D01*
X106516D01*
G01X148065Y-223352D02*
X148939Y-222477D01*
X149594Y-221019D01*
X150031Y-218976D01*
X149594Y-217227D01*
X148721Y-216060D01*
X147192Y-215185D01*
X141297D01*
Y-232685D01*
X148502D01*
X150031Y-231519D01*
X150904Y-229768D01*
X151341Y-227727D01*
X150904Y-225685D01*
X149594Y-223935D01*
X148065Y-223352D01*
X141297D01*
G01X159452Y-232685D02*
Y-215185D01*
X164692D01*
X166439Y-216060D01*
X167749Y-218102D01*
X168186Y-220435D01*
X167749Y-222768D01*
X166657Y-224518D01*
X164692Y-225394D01*
X159452D01*
G01X-16858Y-187685D02*
Y-170185D01*
X-11181Y-184768D01*
X-5504Y-170185D01*
Y-187685D01*
G01X6319D02*
X5009Y-187393D01*
X3699Y-186227D01*
X2825Y-184185D01*
X2389Y-181852D01*
X2825Y-179518D01*
X3699Y-177477D01*
X5009Y-176310D01*
X6319Y-176019D01*
X7629Y-176310D01*
X8939Y-177477D01*
X9812Y-179518D01*
X10031Y-181852D01*
X9812Y-184185D01*
X8939Y-186227D01*
X7629Y-187393D01*
X6319Y-187685D01*
G01X27749Y-170185D02*
Y-187685D01*
G01Y-185061D02*
X26876Y-186519D01*
X25565Y-187393D01*
X24037Y-187685D01*
X22291Y-187102D01*
X20981Y-185644D01*
X20107Y-183894D01*
X19889Y-181852D01*
X20107Y-179810D01*
X20981Y-178060D01*
X22291Y-176602D01*
X24037Y-176019D01*
X25565Y-176310D01*
X26657Y-176894D01*
X27749Y-178060D01*
G01X38044Y-179810D02*
X45031D01*
X44376Y-177768D01*
X43284Y-176602D01*
X41756Y-176019D01*
X40227Y-176310D01*
X38917Y-177185D01*
X38044Y-179227D01*
X37607Y-180977D01*
Y-182727D01*
X38044Y-184477D01*
X39136Y-186227D01*
X40446Y-187393D01*
X41974Y-187685D01*
X43502Y-187102D01*
X45031Y-185352D01*
G01X58819Y-187685D02*
Y-170185D01*
G01X204702Y-187685D02*
Y-170185D01*
X209942D01*
X211689Y-171060D01*
X212999Y-173102D01*
X213436Y-175435D01*
X212999Y-177768D01*
X211907Y-179518D01*
X209942Y-180394D01*
X204702D01*
G01X231372Y-171644D02*
X230062Y-170768D01*
X228534Y-170185D01*
X226787D01*
X224822Y-171060D01*
X223294Y-172518D01*
X222202Y-174269D01*
X221329Y-177185D01*
X221110Y-179810D01*
X221547Y-182435D01*
X222202Y-184185D01*
X223512Y-185935D01*
X225041Y-187102D01*
X226569Y-187685D01*
X228097D01*
X229626Y-187102D01*
X230936Y-186227D01*
X232028Y-185061D01*
G01X245815Y-178352D02*
X246689Y-177477D01*
X247344Y-176019D01*
X247781Y-173976D01*
X247344Y-172227D01*
X246471Y-171060D01*
X244942Y-170185D01*
X239047D01*
Y-187685D01*
X246252D01*
X247781Y-186519D01*
X248654Y-184768D01*
X249091Y-182727D01*
X248654Y-180685D01*
X247344Y-178935D01*
X245815Y-178352D01*
X239047D01*
G01X255019Y-193518D02*
X268119D01*
G01X274047Y-187685D02*
Y-170185D01*
X284091Y-187685D01*
Y-170185D01*
G01X296569Y-187685D02*
X294822Y-187393D01*
X293294Y-186227D01*
X291984Y-184477D01*
X291110Y-182435D01*
X290674Y-180102D01*
Y-177768D01*
X291110Y-175435D01*
X291984Y-173393D01*
X293294Y-171644D01*
X294822Y-170477D01*
X296569Y-170185D01*
X298315Y-170477D01*
X299844Y-171644D01*
X301154Y-173393D01*
X302028Y-175435D01*
X302464Y-177768D01*
Y-180102D01*
X302028Y-182435D01*
X301154Y-184477D01*
X299844Y-186227D01*
X298315Y-187393D01*
X296569Y-187685D01*
G01X217819Y-232685D02*
Y-215185D01*
X215199Y-218685D01*
G01Y-232685D02*
X220439D01*
G01X234882D02*
X235319Y-228894D01*
X235974Y-225685D01*
X236847Y-222768D01*
X237939Y-219560D01*
X239686Y-215185D01*
X230952D01*
G01X248016Y-229185D02*
X249325Y-231227D01*
X251072Y-232393D01*
X253037Y-232685D01*
X254784Y-232393D01*
X256531Y-230935D01*
X257622Y-229185D01*
X257841Y-227435D01*
X257404Y-225394D01*
X255876Y-223935D01*
X254347Y-223352D01*
X252382D01*
G01X254347D02*
X255657Y-222477D01*
X256749Y-221019D01*
X257186Y-219269D01*
X256749Y-217518D01*
X255657Y-216060D01*
X253692Y-215185D01*
X251727Y-215477D01*
X249762Y-216644D01*
G01X270319Y-215185D02*
X268572Y-215768D01*
X267262Y-217227D01*
X266389Y-218976D01*
X265734Y-221310D01*
X265516Y-223935D01*
X265734Y-226560D01*
X266389Y-228894D01*
X267262Y-230644D01*
X268572Y-232102D01*
X270319Y-232685D01*
X272065Y-232102D01*
X273376Y-230644D01*
X274249Y-228894D01*
X274904Y-226560D01*
X275122Y-223935D01*
X274904Y-221310D01*
X274249Y-218976D01*
X273376Y-217227D01*
X272065Y-215768D01*
X270319Y-215185D01*
G01X287819Y-232685D02*
Y-215185D01*
X285199Y-218685D01*
G01Y-232685D02*
X290439D01*
G01X365784Y-230352D02*
X367531Y-231810D01*
X369496Y-232685D01*
X371242D01*
X372989Y-231810D01*
X374299Y-230352D01*
X374954Y-228310D01*
X374517Y-226269D01*
X373426Y-224518D01*
X371461Y-223352D01*
X368841Y-222768D01*
X367312Y-221602D01*
X366657Y-219560D01*
X367094Y-217518D01*
X368186Y-216060D01*
X369714Y-215185D01*
X371242D01*
X372771Y-215768D01*
X374081Y-217227D01*
G01X382410Y-232685D02*
X387869Y-215185D01*
X393328Y-232685D01*
G01X391362Y-226560D02*
X384375D01*
G01X347410Y-170185D02*
X352869Y-187685D01*
X358328Y-170185D01*
G01X374736Y-187685D02*
X366002D01*
Y-170185D01*
X374736D01*
G01X371242Y-178643D02*
X366002D01*
G01X383502Y-187685D02*
Y-170185D01*
X388961D01*
X390707Y-171060D01*
X391799Y-172227D01*
X392236Y-174560D01*
X391799Y-176894D01*
X390489Y-178352D01*
X388961Y-179227D01*
X383502D01*
G01X388961D02*
X392236Y-187685D01*
G01X405369Y-188268D02*
X404932Y-187977D01*
Y-187393D01*
X405369Y-187102D01*
X405806Y-187393D01*
Y-187977D01*
X405369Y-188268D01*
G01X480952Y-170185D02*
Y-187685D01*
X489686D01*
G01X506749D02*
Y-176019D01*
G01Y-178060D02*
X505876Y-176894D01*
X504565Y-176310D01*
X503037Y-176019D01*
X501509Y-176602D01*
X500199Y-177768D01*
X499325Y-179518D01*
X498889Y-181852D01*
X499325Y-184185D01*
X500199Y-185935D01*
X501509Y-187102D01*
X503037Y-187685D01*
X504565Y-187393D01*
X505876Y-186519D01*
X506749Y-185352D01*
G01X515734Y-192935D02*
X517044Y-193518D01*
X518791Y-192935D01*
X519882Y-191769D01*
X520756Y-190310D01*
X522065Y-185644D01*
X524904Y-176019D01*
G01X517917D02*
X522065Y-185644D01*
G01X534544Y-179810D02*
X541531D01*
X540876Y-177768D01*
X539784Y-176602D01*
X538256Y-176019D01*
X536727Y-176310D01*
X535417Y-177185D01*
X534544Y-179227D01*
X534107Y-180977D01*
Y-182727D01*
X534544Y-184477D01*
X535636Y-186227D01*
X536946Y-187393D01*
X538474Y-187685D01*
X540002Y-187102D01*
X541531Y-185352D01*
G01X552262Y-187685D02*
Y-176019D01*
G01Y-178352D02*
X553354Y-177185D01*
X554446Y-176310D01*
X555974Y-176019D01*
X557065Y-176310D01*
X558376Y-177185D01*
G01X507202Y-215185D02*
Y-232685D01*
X515936D01*
G01X529069D02*
Y-215185D01*
X526449Y-218685D01*
G01Y-232685D02*
X531689D01*
G01X623066Y-187685D02*
Y-170185D01*
X627432D01*
X629179Y-171060D01*
X630489Y-172227D01*
X631581Y-173976D01*
X632454Y-176019D01*
X632672Y-178935D01*
X632454Y-181852D01*
X631581Y-183894D01*
X630489Y-185644D01*
X629179Y-186810D01*
X627432Y-187685D01*
X623066D01*
G01X642094Y-179810D02*
X649081D01*
X648426Y-177768D01*
X647334Y-176602D01*
X645806Y-176019D01*
X644277Y-176310D01*
X642967Y-177185D01*
X642094Y-179227D01*
X641657Y-180977D01*
Y-182727D01*
X642094Y-184477D01*
X643186Y-186227D01*
X644496Y-187393D01*
X646024Y-187685D01*
X647552Y-187102D01*
X649081Y-185352D01*
G01X659594Y-185644D02*
X660686Y-186810D01*
X662214Y-187685D01*
X663524D01*
X664834Y-187102D01*
X665707Y-186227D01*
X666144Y-185061D01*
X665926Y-183310D01*
X665052Y-182435D01*
X661122Y-180685D01*
X660249Y-178643D01*
X660686Y-177185D01*
X661559Y-176310D01*
X662869Y-176019D01*
X664179Y-176310D01*
X665489Y-177185D01*
G01X680369Y-176019D02*
Y-187685D01*
G01Y-171352D02*
X679932Y-171060D01*
Y-170477D01*
X680369Y-170185D01*
X680806Y-170477D01*
Y-171060D01*
X680369Y-171352D01*
G01X694812Y-192060D02*
X696341Y-193227D01*
X698087Y-193518D01*
X699615Y-193227D01*
X700926Y-191769D01*
X701799Y-189727D01*
Y-176019D01*
G01Y-178352D02*
X700926Y-177185D01*
X699615Y-176310D01*
X698087Y-176019D01*
X696341Y-176602D01*
X695249Y-177768D01*
X694375Y-179810D01*
X693939Y-181852D01*
X694157Y-183602D01*
X695031Y-185644D01*
X696341Y-187102D01*
X698087Y-187685D01*
X699397Y-187393D01*
X700926Y-186227D01*
X701799Y-185061D01*
G01X711657Y-187685D02*
Y-176019D01*
G01Y-178935D02*
X712531Y-177477D01*
X713841Y-176310D01*
X715587Y-176019D01*
X717115Y-176310D01*
X718426Y-177477D01*
X719081Y-179518D01*
Y-187685D01*
G01X729594Y-179810D02*
X736581D01*
X735926Y-177768D01*
X734834Y-176602D01*
X733306Y-176019D01*
X731777Y-176310D01*
X730467Y-177185D01*
X729594Y-179227D01*
X729157Y-180977D01*
Y-182727D01*
X729594Y-184477D01*
X730686Y-186227D01*
X731996Y-187393D01*
X733524Y-187685D01*
X735052Y-187102D01*
X736581Y-185352D01*
G01X747312Y-187685D02*
Y-176019D01*
G01Y-178352D02*
X748404Y-177185D01*
X749496Y-176310D01*
X751024Y-176019D01*
X752115Y-176310D01*
X753426Y-177185D01*
G01X664179Y-223935D02*
X668546D01*
Y-229185D01*
X667236Y-230935D01*
X665707Y-232102D01*
X663524Y-232685D01*
X661341Y-232102D01*
X659812Y-230935D01*
X658502Y-229185D01*
X657629Y-227143D01*
X657192Y-224810D01*
Y-222768D01*
X657629Y-221019D01*
X658502Y-218976D01*
X659812Y-217227D01*
X661122Y-216060D01*
X662869Y-215185D01*
X664397D01*
X666144Y-215768D01*
X667454Y-216935D01*
G01X684736Y-232685D02*
X676002D01*
Y-215185D01*
X684736D01*
G01X681242Y-223643D02*
X676002D01*
G01X693502Y-215185D02*
Y-232685D01*
X702236D01*
G01X715369D02*
X713622Y-232393D01*
X712094Y-231227D01*
X710784Y-229477D01*
X709910Y-227435D01*
X709474Y-225102D01*
Y-222768D01*
X709910Y-220435D01*
X710784Y-218393D01*
X712094Y-216644D01*
X713622Y-215477D01*
X715369Y-215185D01*
X717115Y-215477D01*
X718644Y-216644D01*
X719954Y-218393D01*
X720828Y-220435D01*
X721264Y-222768D01*
Y-225102D01*
X720828Y-227435D01*
X719954Y-229477D01*
X718644Y-231227D01*
X717115Y-232393D01*
X715369Y-232685D01*
G01X794069Y-215185D02*
X792322Y-215768D01*
X791012Y-217227D01*
X790139Y-218976D01*
X789484Y-221310D01*
X789266Y-223935D01*
X789484Y-226560D01*
X790139Y-228894D01*
X791012Y-230644D01*
X792322Y-232102D01*
X794069Y-232685D01*
X795815Y-232102D01*
X797126Y-230644D01*
X797999Y-228894D01*
X798654Y-226560D01*
X798872Y-223935D01*
X798654Y-221310D01*
X797999Y-218976D01*
X797126Y-217227D01*
X795815Y-215768D01*
X794069Y-215185D01*
G01X807421Y-225394D02*
X808949Y-223352D01*
X810259Y-222185D01*
X812006Y-221602D01*
X813534Y-222185D01*
X814626Y-223352D01*
X815499Y-225102D01*
X815717Y-227143D01*
X815499Y-228894D01*
X814626Y-230644D01*
X813315Y-232102D01*
X811787Y-232685D01*
X810041Y-232102D01*
X808512Y-230352D01*
X807639Y-227727D01*
X807421Y-224810D01*
X807857Y-221019D01*
X808512Y-218976D01*
X809604Y-216935D01*
X811132Y-215477D01*
X812661Y-215185D01*
X814189Y-215768D01*
X815281Y-217227D01*
G01X825139Y-233268D02*
X832999Y-215185D01*
G01X842421Y-218102D02*
X843731Y-216352D01*
X845259Y-215477D01*
X847006Y-215185D01*
X849189Y-215768D01*
X850717Y-217227D01*
X851154Y-218976D01*
X850936Y-220727D01*
X850062Y-222185D01*
X845696Y-225102D01*
X843731Y-227143D01*
X842421Y-230061D01*
X841984Y-232685D01*
X851154D01*
G01X859921Y-218102D02*
X861231Y-216352D01*
X862759Y-215477D01*
X864506Y-215185D01*
X866689Y-215768D01*
X868217Y-217227D01*
X868654Y-218976D01*
X868436Y-220727D01*
X867562Y-222185D01*
X863196Y-225102D01*
X861231Y-227143D01*
X859921Y-230061D01*
X859484Y-232685D01*
X868654D01*
G01X877639Y-233268D02*
X885499Y-215185D01*
G01X894921Y-218102D02*
X896231Y-216352D01*
X897759Y-215477D01*
X899506Y-215185D01*
X901689Y-215768D01*
X903217Y-217227D01*
X903654Y-218976D01*
X903436Y-220727D01*
X902562Y-222185D01*
X898196Y-225102D01*
X896231Y-227143D01*
X894921Y-230061D01*
X894484Y-232685D01*
X903654D01*
G01X916569Y-215185D02*
X914822Y-215768D01*
X913512Y-217227D01*
X912639Y-218976D01*
X911984Y-221310D01*
X911766Y-223935D01*
X911984Y-226560D01*
X912639Y-228894D01*
X913512Y-230644D01*
X914822Y-232102D01*
X916569Y-232685D01*
X918315Y-232102D01*
X919626Y-230644D01*
X920499Y-228894D01*
X921154Y-226560D01*
X921372Y-223935D01*
X921154Y-221310D01*
X920499Y-218976D01*
X919626Y-217227D01*
X918315Y-215768D01*
X916569Y-215185D01*
G01X934069Y-232685D02*
Y-215185D01*
X931449Y-218685D01*
G01Y-232685D02*
X936689D01*
G01X951132D02*
X951569Y-228894D01*
X952224Y-225685D01*
X953097Y-222768D01*
X954189Y-219560D01*
X955936Y-215185D01*
X947202D01*
G01X841766Y-187685D02*
Y-170185D01*
X846132D01*
X847879Y-171060D01*
X849189Y-172227D01*
X850281Y-173976D01*
X851154Y-176019D01*
X851372Y-178935D01*
X851154Y-181852D01*
X850281Y-183894D01*
X849189Y-185644D01*
X847879Y-186810D01*
X846132Y-187685D01*
X841766D01*
G01X867999D02*
Y-176019D01*
G01Y-178060D02*
X867126Y-176894D01*
X865815Y-176310D01*
X864287Y-176019D01*
X862759Y-176602D01*
X861449Y-177768D01*
X860575Y-179518D01*
X860139Y-181852D01*
X860575Y-184185D01*
X861449Y-185935D01*
X862759Y-187102D01*
X864287Y-187685D01*
X865815Y-187393D01*
X867126Y-186519D01*
X867999Y-185352D01*
G01X881569Y-170185D02*
Y-187685D01*
G01X878512Y-176019D02*
X884626D01*
G01X895794Y-179810D02*
X902781D01*
X902126Y-177768D01*
X901034Y-176602D01*
X899506Y-176019D01*
X897977Y-176310D01*
X896667Y-177185D01*
X895794Y-179227D01*
X895357Y-180977D01*
Y-182727D01*
X895794Y-184477D01*
X896886Y-186227D01*
X898196Y-187393D01*
X899724Y-187685D01*
X901252Y-187102D01*
X902781Y-185352D01*
G54D31*
X295472Y65571D03*
Y108287D03*
X330590Y65571D03*
Y108287D03*
G54D13*
X20847Y701602D03*
X32739Y30456D03*
X514356Y57612D03*
G54D22*
X192500Y32100D03*
X188300Y75000D03*
X226520Y33897D03*
X222194Y74962D03*
X469635Y224263D03*
X494300Y158300D03*
X497446Y224052D03*
X517300Y158500D03*
G54D41*
G01X320965Y32050D02*
Y27735D01*
X322100Y26600D01*
G01X305250Y32000D02*
Y30250D01*
X303900Y28900D01*
G01X308750Y32000D02*
X313250D01*
G01D02*
Y27850D01*
X313900Y27200D01*
G54D14*
X48300Y76000D03*
Y79500D03*
X225756Y38299D03*
X221430Y79364D03*
X296700Y164800D03*
X307800Y209500D03*
Y206000D03*
G54D32*
X316700Y32000D03*
X308700D03*
X321200Y142000D03*
X309200Y133500D03*
X339700Y20000D03*
X328700Y142000D03*
X352200Y29500D03*
X360200D03*
G54D23*
X200674Y38941D03*
X196830Y81864D03*
G54D42*
G01X389331Y137992D02*
X388257Y136918D01*
Y134032D01*
X387790Y131734D01*
X357536Y86026D01*
X341193Y75209D01*
X324100Y71732D01*
X320069Y74400D01*
X318584Y81688D01*
X321331Y85834D01*
X324766Y86533D01*
X326313D01*
X327114Y87334D01*
G01X384331Y137992D02*
X386517Y135806D01*
Y134208D01*
X386152Y132412D01*
X383942Y129073D01*
X383941D01*
X382694Y128819D01*
X381303Y126718D01*
X381557Y125470D01*
X380166Y123369D01*
X378919Y123115D01*
X377528Y121014D01*
X377781Y119766D01*
X371381Y110098D01*
X370133Y109844D01*
X368742Y107743D01*
X368996Y106495D01*
X367605Y104394D01*
X366358Y104140D01*
X364967Y102039D01*
X365221Y100791D01*
X363830Y98690D01*
X362583Y98436D01*
X361192Y96335D01*
X361446Y95087D01*
X360055Y92986D01*
X358808Y92732D01*
X357417Y90631D01*
X357671Y89383D01*
X356280Y87282D01*
X354179Y85891D01*
X352931Y86145D01*
X350830Y84754D01*
X350576Y83507D01*
X348475Y82116D01*
X347227Y82370D01*
X345126Y80979D01*
X344872Y79731D01*
X340515Y76847D01*
X337866Y76308D01*
X336804Y77011D01*
X334335Y76509D01*
X333632Y75447D01*
X331163Y74945D01*
X330101Y75647D01*
X327632Y75145D01*
X326929Y74083D01*
X324460Y73581D01*
X321631Y75454D01*
X320434Y81328D01*
X322384Y84272D01*
X324942Y84793D01*
X326274D01*
X327114Y83953D01*
Y83334D01*
G01X389331Y203740D02*
X387907Y202316D01*
Y199005D01*
X385497Y195362D01*
X365401Y182061D01*
X352184Y162092D01*
X346497Y134138D01*
X347200Y133076D01*
X346698Y130607D01*
X345636Y129904D01*
X345134Y127435D01*
X345836Y126373D01*
X345334Y123904D01*
X344272Y123201D01*
X343770Y120732D01*
X344472Y119670D01*
X343970Y117201D01*
X342908Y116498D01*
X342406Y114029D01*
X343108Y112967D01*
X342606Y110498D01*
X341544Y109795D01*
X341042Y107326D01*
X335150Y98425D01*
X334260Y94053D01*
X335118Y89830D01*
X340426Y86317D01*
X341898D01*
X343028Y87447D01*
G01X384331Y203740D02*
X386167Y201904D01*
Y199529D01*
X384241Y196618D01*
X364145Y183317D01*
X350546Y162770D01*
X339404Y108004D01*
X333512Y99103D01*
X332484Y94053D01*
X333556Y88777D01*
X339902Y84577D01*
X341898D01*
X343028Y83447D01*
G54D33*
X313300Y32000D03*
X305300D03*
X317800Y142000D03*
X305800Y133500D03*
X336300Y20000D03*
X325300Y142000D03*
X348800Y29500D03*
X356800D03*
G54D15*
X44700Y76000D03*
Y79500D03*
X222156Y38299D03*
X217830Y79364D03*
X293100Y164800D03*
X304200Y209500D03*
Y206000D03*
G54D24*
X204274Y38941D03*
X200430Y81864D03*
G54D25*
X207500Y74700D03*
X211100Y32000D03*
X320946Y42829D03*
X324423Y42824D03*
X479900Y223700D03*
X502868Y159486D03*
G54D34*
X332000Y234500D03*
G54D16*
X68112Y15039D03*
Y59528D03*
X233462Y15039D03*
Y59528D03*
X359156Y142992D03*
Y208740D03*
X524506Y142992D03*
Y208740D03*
G54D26*
X207500Y78300D03*
X211100Y35600D03*
X320946Y46429D03*
X324423Y46424D03*
X479900Y227300D03*
X502868Y163086D03*
G54D35*
X327151Y153540D03*
X357000Y41200D03*
G54D17*
G01X-139981Y-146685D02*
G02I-12000J0D01*
G01X-145131D02*
G02I-6850J0D01*
G01X-135981D02*
X-167981D01*
G01X-135981Y-162685D02*
Y-242685D01*
G01D02*
X971619D01*
G01X-135981Y-198185D02*
X971619D01*
G01X-151981Y-162685D02*
Y-130685D01*
G01X-135981Y-162685D02*
X971619D01*
G01X73567Y4087D02*
X66757D01*
X57900Y12944D01*
Y64900D01*
X61000Y68000D01*
X76600D01*
G01X184119Y-162685D02*
Y-242685D01*
G01X173287Y10039D02*
Y13191D01*
G01Y10039D02*
X174700Y13248D01*
G01X178287Y10039D02*
Y13191D01*
G01Y10039D02*
X180766Y12518D01*
G01X183287Y10039D02*
Y13191D01*
G01Y10039D02*
X185766Y12518D01*
G01X173287Y54528D02*
Y57680D01*
G01Y54528D02*
X174700Y57737D01*
G01X178287Y54528D02*
Y57680D01*
G01Y54528D02*
X180766Y57007D01*
G01X183287Y54528D02*
Y57680D01*
G01Y54528D02*
X185766Y57007D01*
G01X203287Y10039D02*
Y13191D01*
G01X200808Y12518D02*
X203287Y10039D01*
G01X208287D02*
Y13191D01*
G01Y10039D02*
X210766Y12518D01*
G01X203287Y54528D02*
Y57680D01*
G01X200808Y57007D02*
X203287Y54528D01*
G01X208287Y51376D02*
Y54528D01*
G01D02*
Y57680D01*
G01X220310Y4087D02*
X263862D01*
X268045Y8270D01*
G01X213287Y10039D02*
Y13191D01*
G01Y10039D02*
X216439D01*
G01X214956Y35549D02*
X216749D01*
X218600Y37400D01*
G01X222206Y38299D02*
Y41500D01*
G01X213287Y51376D02*
Y54528D01*
G01D02*
Y57680D01*
G01Y54528D02*
X216439D01*
G01X217880Y79364D02*
Y83600D01*
G01X211500Y78250D02*
Y81900D01*
X213100Y83500D01*
G01X268045Y8270D02*
Y11830D01*
X258088Y21787D01*
G01X286638Y33917D02*
X313645Y60924D01*
X345076D01*
X349229Y56771D01*
Y52810D01*
G01X321619Y-162685D02*
Y-242685D01*
G01X316750Y32000D02*
Y25950D01*
X319600Y23100D01*
X328066D01*
X332666Y27700D01*
G01X317750Y142000D02*
Y138285D01*
X319688Y136347D01*
X329659D01*
X340698Y147386D01*
Y154738D01*
G01X305750Y133500D02*
X302000D01*
G01X332050Y33271D02*
X335929D01*
X338230Y30970D01*
Y25171D01*
X336250Y23191D01*
Y20000D01*
G01D02*
X332778D01*
G01X336779Y165718D02*
X332000Y170497D01*
G01D02*
Y183500D01*
G01X348750Y29500D02*
X346976Y31274D01*
Y36568D01*
X348971Y38563D01*
Y41813D01*
G01X412381Y214113D02*
Y217165D01*
G01D02*
Y220217D01*
G01X409729Y217165D02*
X412381D01*
G01X431281Y214113D02*
Y217165D01*
G01D02*
Y220217D01*
G01Y217165D02*
X433933D01*
G01X436619Y-162685D02*
Y-242685D01*
G01X464331Y137992D02*
Y141144D01*
G01Y137992D02*
X465744Y141201D01*
G01X469331Y137992D02*
Y141144D01*
G01Y137992D02*
X471810Y140471D01*
G01X474331Y137992D02*
Y141144D01*
G01X471852Y140471D02*
X474331Y137992D01*
G01X464331Y203740D02*
Y206892D01*
G01X461852Y206219D02*
X464331Y203740D01*
G01X469331Y200588D02*
Y203740D01*
G01D02*
Y206892D01*
G01X474331Y200588D02*
Y203740D01*
G01D02*
Y206892D01*
G01X479900Y227250D02*
X476600D01*
G01X494331Y137992D02*
Y141144D01*
G01Y137992D02*
X496810Y140471D01*
G01X499331Y137992D02*
X501810Y140471D01*
G01X499331Y137992D02*
X500744Y141201D01*
G01X502868Y163036D02*
Y166448D01*
G01X494331Y203740D02*
Y206892D01*
G01X491852Y206219D02*
X494331Y203740D01*
G01X499331Y200588D02*
Y203740D01*
G01D02*
Y206892D01*
G01X483700Y227250D02*
Y230522D01*
G01X504331Y137992D02*
Y141144D01*
G01Y137992D02*
X506810Y140471D01*
G01X506868Y163036D02*
Y166599D01*
G01X504331Y200588D02*
Y203740D01*
G01D02*
Y206892D01*
G01Y203740D02*
X507483D01*
G01X604119Y-162685D02*
Y-242685D01*
G01X774119Y-162685D02*
Y-242685D01*
G01X971619Y-162685D02*
Y-242685D01*
G01X999619Y-146685D02*
G02I-12000J0D01*
G01X1003619D02*
X971619D01*
G01X994469D02*
G02I-6850J0D01*
G01X987619Y-162685D02*
Y-130685D01*
X60928Y64173D03*
X73567Y4087D03*
X75100Y36700D03*
X74635Y29153D03*
X76804Y61699D03*
X76600Y68000D03*
X208000Y90000D03*
X204500D03*
X220310Y4087D03*
X222206Y41500D03*
X218600Y37400D03*
X217880Y83600D03*
X213100Y83500D03*
X268045Y8270D03*
X258088Y21787D03*
X273551Y37112D03*
X293146Y81023D03*
X293141Y97997D03*
X279500Y116900D03*
X279437Y120731D03*
X303900Y28900D03*
X313900Y27200D03*
X315166Y52172D03*
X313617Y81023D03*
X321440Y101571D03*
X308208Y101945D03*
X303734Y89882D03*
X324700Y16300D03*
X329962Y56703D03*
X337406Y79575D03*
X341133Y80298D03*
X326892Y79371D03*
X338145Y98740D03*
X337670Y90976D03*
X332822Y103140D03*
X327057Y90943D03*
X343028Y87447D03*
X327114Y87334D03*
X340874Y96311D03*
X325404Y101215D03*
X343028Y83447D03*
X327114Y83334D03*
X340874Y92311D03*
X329404Y101215D03*
X336238Y148951D03*
X345642Y90134D03*
X506868Y166599D03*
G54D27*
X214956Y32099D03*
X211500Y74800D03*
X320965Y32100D03*
X325152Y32095D03*
X483700Y223800D03*
X506868Y159586D03*
G54D36*
X327151Y150140D03*
X357000Y37800D03*
G54D18*
X93287Y10039D03*
X88287D03*
X93287Y54528D03*
X88287D03*
X118287Y10039D03*
X113287D03*
X108287D03*
X103287D03*
X98287D03*
X118287Y54528D03*
X113287D03*
X108287D03*
X103287D03*
X98287D03*
X163287Y10039D03*
X158287D03*
X153287D03*
X148287D03*
X143287D03*
X163287Y54528D03*
X158287D03*
X153287D03*
X148287D03*
X143287D03*
X183287Y10039D03*
X178287D03*
X173287D03*
X168287D03*
X183287Y54528D03*
X178287D03*
X173287D03*
X168287D03*
X208287Y10039D03*
X203287D03*
X198287D03*
X193287D03*
X188287D03*
X208287Y54528D03*
X203287D03*
X198287D03*
X193287D03*
X188287D03*
X213287Y10039D03*
Y54528D03*
X389331Y137992D03*
X384331D03*
X379331D03*
X389331Y203740D03*
X384331D03*
X379331D03*
X409331Y137992D03*
X404331D03*
X399331D03*
X394331D03*
X409331Y203740D03*
X404331D03*
X399331D03*
X394331D03*
X434331Y137992D03*
Y203740D03*
X459331Y137992D03*
X454331D03*
X449331D03*
X444331D03*
X439331D03*
X459331Y203740D03*
X454331D03*
X449331D03*
X444331D03*
X439331D03*
X479331Y137992D03*
X474331D03*
X469331D03*
X464331D03*
X479331Y203740D03*
X474331D03*
X469331D03*
X464331D03*
X504331Y137992D03*
X499331D03*
X494331D03*
X489331D03*
X484331D03*
X504331Y203740D03*
X499331D03*
X494331D03*
X489331D03*
X484331D03*
G54D28*
X214956Y35499D03*
X211500Y78200D03*
X320965Y35500D03*
X325152Y35495D03*
X483700Y227200D03*
X506868Y162986D03*
G54D19*
X140237Y23464D03*
X137087D03*
X133937D03*
X130787D03*
X127637D03*
X124487D03*
X121337D03*
X140237Y67953D03*
X137087D03*
X133937D03*
X130787D03*
X127637D03*
X124487D03*
X121337D03*
X412381Y151417D03*
Y217165D03*
X431281Y151417D03*
X428131D03*
X424981D03*
X421831D03*
X418681D03*
X415531D03*
X431281Y217165D03*
X428131D03*
X424981D03*
X421831D03*
X418681D03*
X415531D03*
G54D37*
X331151Y153640D03*
X361000Y41300D03*
G54D29*
X228630Y76864D03*
Y85564D03*
X244456Y33299D03*
X233456D03*
X244456Y41999D03*
X233456D03*
X239630Y76864D03*
Y85564D03*
X289800Y150000D03*
X300800D03*
X289800Y158700D03*
X300800D03*
G54D38*
X331151Y150040D03*
X361000Y37700D03*
G54D39*
X484960Y86811D03*
X496771D03*
X508583D03*
X520394D03*
M02*
